(kicad_pcb
	(version 20260206)
	(generator "pcbnew")
	(generator_version "10.0")
	(general
		(thickness 1.6)
		(legacy_teardrops no)
	)
	(paper "A4")
	(title_block
		(title "01162023_DA0F0TEBIF0_F0T_Expander_BD_F_brd_V02_OCP.brd")
		(comment 1 "Grand Teton / footprints 3719-3725 of 9728")
	)
	(layers
		(0 "F.Cu" signal "TOP")
		(4 "In1.Cu" signal "GND")
		(6 "In2.Cu" signal "VCC")
		(8 "In3.Cu" signal "VCC1")
		(10 "In4.Cu" signal "GND1")
		(12 "In5.Cu" signal "IN1")
		(14 "In6.Cu" signal "GND2")
		(16 "In7.Cu" signal "IN2")
		(18 "In8.Cu" signal "GND3")
		(20 "In9.Cu" signal "IN3")
		(22 "In10.Cu" signal "GND4")
		(24 "In11.Cu" signal "IN4")
		(26 "In12.Cu" signal "GND5")
		(28 "In13.Cu" signal "IN5")
		(30 "In14.Cu" signal "GND6")
		(32 "In15.Cu" signal "IN6")
		(34 "In16.Cu" signal "GND7")
		(2 "B.Cu" signal "BOTTOM")
		(9 "F.Adhes" user "F.Adhesive")
		(11 "B.Adhes" user "B.Adhesive")
		(13 "F.Paste" user "Package Geometry/Pastemask Top")
		(15 "B.Paste" user "Package Geometry/Pastemask Bottom")
		(5 "F.SilkS" user "Ref Des/Silkscreen Top")
		(7 "B.SilkS" user "Ref Des/Silkscreen Bottom")
		(1 "F.Mask" user "Board Geometry/Soldermask Top")
		(3 "B.Mask" user "Board Geometry/Soldermask Bottom")
		(17 "Dwgs.User" user "User.Drawings")
		(19 "Cmts.User" user "User.Comments")
		(21 "Eco1.User" user "User.Eco1")
		(23 "Eco2.User" user "User.Eco2")
		(25 "Edge.Cuts" user "Board Geometry/Outline")
		(27 "Margin" user)
		(31 "F.CrtYd" user "Package Geometry/Place Bound Top")
		(29 "B.CrtYd" user "Package Geometry/Place Bound Bottom")
		(35 "F.Fab" user "Ref Des/Assembly Top")
		(33 "B.Fab" user "Ref Des/Assembly Bottom")
	)
	(footprint ""
		(layer "F.Cu")
		(at 343.615518 -201.168 90)
		(property "Reference" "R6417"
			(at 0 0 90)
			(layer "F.SilkS")
			(hide yes)
			(effects
				(font
					(size 1.27 1.27)
				)
			)
		)
		(property "Value" ""
			(at 0 0 90)
			(layer "F.Fab")
			(effects
				(font
					(size 1.27 1.27)
				)
			)
		)
		(duplicate_pad_numbers_are_jumpers no)
		(fp_line
			(start 0.7874 -0.4064)
			(end 0.7874 0.4064)
			(stroke
				(width 0.1524)
				(type default)
			)
			(layer "F.SilkS")
		)
		(fp_line
			(start -0.7874 -0.4064)
			(end 0.7874 -0.4064)
			(stroke
				(width 0.1524)
				(type default)
			)
			(layer "F.SilkS")
		)
		(fp_line
			(start 0.7874 0.4064)
			(end -0.7874 0.4064)
			(stroke
				(width 0.1524)
				(type default)
			)
			(layer "F.SilkS")
		)
		(fp_line
			(start -0.7874 0.4064)
			(end -0.7874 -0.4064)
			(stroke
				(width 0.1524)
				(type default)
			)
			(layer "F.SilkS")
		)
		(fp_line
			(start -0.12065 -0.305054)
			(end -0.12065 -0.2794)
			(stroke
				(width 0.1)
				(type default)
			)
			(layer "F.Fab")
		)
		(fp_line
			(start -0.67945 -0.305054)
			(end -0.12065 -0.305054)
			(stroke
				(width 0.1)
				(type default)
			)
			(layer "F.Fab")
		)
		(fp_line
			(start 0.67945 -0.3048)
			(end 0.67945 0.3048)
			(stroke
				(width 0.1)
				(type default)
			)
			(layer "F.Fab")
		)
		(fp_line
			(start 0.12065 -0.3048)
			(end 0.67945 -0.3048)
			(stroke
				(width 0.1)
				(type default)
			)
			(layer "F.Fab")
		)
		(fp_line
			(start 0.12065 -0.2794)
			(end 0.12065 -0.3048)
			(stroke
				(width 0.1)
				(type default)
			)
			(layer "F.Fab")
		)
		(fp_line
			(start -0.12065 -0.2794)
			(end 0.12065 -0.2794)
			(stroke
				(width 0.1)
				(type default)
			)
			(layer "F.Fab")
		)
		(fp_line
			(start 0.120396 0.2794)
			(end -0.12065 0.2794)
			(stroke
				(width 0.1)
				(type default)
			)
			(layer "F.Fab")
		)
		(fp_line
			(start -0.12065 0.2794)
			(end -0.12065 0.3048)
			(stroke
				(width 0.1)
				(type default)
			)
			(layer "F.Fab")
		)
		(fp_line
			(start 0.67945 0.3048)
			(end 0.120396 0.3048)
			(stroke
				(width 0.1)
				(type default)
			)
			(layer "F.Fab")
		)
		(fp_line
			(start 0.120396 0.3048)
			(end 0.120396 0.2794)
			(stroke
				(width 0.1)
				(type default)
			)
			(layer "F.Fab")
		)
		(fp_line
			(start -0.12065 0.3048)
			(end -0.67945 0.3048)
			(stroke
				(width 0.1)
				(type default)
			)
			(layer "F.Fab")
		)
		(fp_line
			(start -0.67945 0.3048)
			(end -0.67945 -0.305054)
			(stroke
				(width 0.1)
				(type default)
			)
			(layer "F.Fab")
		)
		(pad "1" smd circle
			(at -0.40005 0 90)
			(size 0 0)
			(layers "F.Cu" "F.Mask" "F.Paste")
			(net "FPGA_PEX0_MODE_SEL1_R")
		)
		(pad "2" smd circle
			(at 0.40005 0 90)
			(size 0 0)
			(layers "F.Cu" "F.Mask" "F.Paste")
			(net "FPGA_PEX0_MODE_SEL1")
		)
	)
	(footprint ""
		(layer "F.Cu")
		(at 92.0496 -304.036476 90)
		(property "Reference" "R1253"
			(at 0 0 90)
			(layer "F.SilkS")
			(hide yes)
			(effects
				(font
					(size 1.27 1.27)
				)
			)
		)
		(property "Value" ""
			(at 0 0 90)
			(layer "F.Fab")
			(effects
				(font
					(size 1.27 1.27)
				)
			)
		)
		(duplicate_pad_numbers_are_jumpers no)
		(fp_line
			(start 0.7874 -0.4064)
			(end 0.7874 0.4064)
			(stroke
				(width 0.1524)
				(type default)
			)
			(layer "F.SilkS")
		)
		(fp_line
			(start -0.7874 -0.4064)
			(end 0.7874 -0.4064)
			(stroke
				(width 0.1524)
				(type default)
			)
			(layer "F.SilkS")
		)
		(fp_line
			(start 0.7874 0.4064)
			(end -0.7874 0.4064)
			(stroke
				(width 0.1524)
				(type default)
			)
			(layer "F.SilkS")
		)
		(fp_line
			(start -0.7874 0.4064)
			(end -0.7874 -0.4064)
			(stroke
				(width 0.1524)
				(type default)
			)
			(layer "F.SilkS")
		)
		(fp_line
			(start -0.12065 -0.305054)
			(end -0.12065 -0.2794)
			(stroke
				(width 0.1)
				(type default)
			)
			(layer "F.Fab")
		)
		(fp_line
			(start -0.67945 -0.305054)
			(end -0.12065 -0.305054)
			(stroke
				(width 0.1)
				(type default)
			)
			(layer "F.Fab")
		)
		(fp_line
			(start 0.67945 -0.3048)
			(end 0.67945 0.3048)
			(stroke
				(width 0.1)
				(type default)
			)
			(layer "F.Fab")
		)
		(fp_line
			(start 0.12065 -0.3048)
			(end 0.67945 -0.3048)
			(stroke
				(width 0.1)
				(type default)
			)
			(layer "F.Fab")
		)
		(fp_line
			(start 0.12065 -0.2794)
			(end 0.12065 -0.3048)
			(stroke
				(width 0.1)
				(type default)
			)
			(layer "F.Fab")
		)
		(fp_line
			(start -0.12065 -0.2794)
			(end 0.12065 -0.2794)
			(stroke
				(width 0.1)
				(type default)
			)
			(layer "F.Fab")
		)
		(fp_line
			(start 0.120396 0.2794)
			(end -0.12065 0.2794)
			(stroke
				(width 0.1)
				(type default)
			)
			(layer "F.Fab")
		)
		(fp_line
			(start -0.12065 0.2794)
			(end -0.12065 0.3048)
			(stroke
				(width 0.1)
				(type default)
			)
			(layer "F.Fab")
		)
		(fp_line
			(start 0.67945 0.3048)
			(end 0.120396 0.3048)
			(stroke
				(width 0.1)
				(type default)
			)
			(layer "F.Fab")
		)
		(fp_line
			(start 0.120396 0.3048)
			(end 0.120396 0.2794)
			(stroke
				(width 0.1)
				(type default)
			)
			(layer "F.Fab")
		)
		(fp_line
			(start -0.12065 0.3048)
			(end -0.67945 0.3048)
			(stroke
				(width 0.1)
				(type default)
			)
			(layer "F.Fab")
		)
		(fp_line
			(start -0.67945 0.3048)
			(end -0.67945 -0.305054)
			(stroke
				(width 0.1)
				(type default)
			)
			(layer "F.Fab")
		)
		(pad "1" smd circle
			(at -0.40005 0 90)
			(size 0 0)
			(layers "F.Cu" "F.Mask" "F.Paste")
			(net "GND")
		)
		(pad "2" smd circle
			(at 0.40005 0 90)
			(size 0 0)
			(layers "F.Cu" "F.Mask" "F.Paste")
			(net "PEX0_SPARE6")
		)
	)
	(footprint ""
		(layer "F.Cu")
		(at 264.670286 -250.070874 -90)
		(property "Reference" "R1344"
			(at 0 0 270)
			(layer "F.SilkS")
			(hide yes)
			(effects
				(font
					(size 1.27 1.27)
				)
			)
		)
		(property "Value" ""
			(at 0 0 270)
			(layer "F.Fab")
			(effects
				(font
					(size 1.27 1.27)
				)
			)
		)
		(duplicate_pad_numbers_are_jumpers no)
		(fp_line
			(start -0.7874 0.4064)
			(end -0.7874 -0.4064)
			(stroke
				(width 0.1524)
				(type default)
			)
			(layer "F.SilkS")
		)
		(fp_line
			(start 0.7874 0.4064)
			(end -0.7874 0.4064)
			(stroke
				(width 0.1524)
				(type default)
			)
			(layer "F.SilkS")
		)
		(fp_line
			(start -0.7874 -0.4064)
			(end 0.7874 -0.4064)
			(stroke
				(width 0.1524)
				(type default)
			)
			(layer "F.SilkS")
		)
		(fp_line
			(start 0.7874 -0.4064)
			(end 0.7874 0.4064)
			(stroke
				(width 0.1524)
				(type default)
			)
			(layer "F.SilkS")
		)
		(fp_line
			(start -0.67945 0.3048)
			(end -0.67945 -0.305054)
			(stroke
				(width 0.1)
				(type default)
			)
			(layer "F.Fab")
		)
		(fp_line
			(start -0.12065 0.3048)
			(end -0.67945 0.3048)
			(stroke
				(width 0.1)
				(type default)
			)
			(layer "F.Fab")
		)
		(fp_line
			(start 0.120396 0.3048)
			(end 0.120396 0.2794)
			(stroke
				(width 0.1)
				(type default)
			)
			(layer "F.Fab")
		)
		(fp_line
			(start 0.67945 0.3048)
			(end 0.120396 0.3048)
			(stroke
				(width 0.1)
				(type default)
			)
			(layer "F.Fab")
		)
		(fp_line
			(start -0.12065 0.2794)
			(end -0.12065 0.3048)
			(stroke
				(width 0.1)
				(type default)
			)
			(layer "F.Fab")
		)
		(fp_line
			(start 0.120396 0.2794)
			(end -0.12065 0.2794)
			(stroke
				(width 0.1)
				(type default)
			)
			(layer "F.Fab")
		)
		(fp_line
			(start -0.12065 -0.2794)
			(end 0.12065 -0.2794)
			(stroke
				(width 0.1)
				(type default)
			)
			(layer "F.Fab")
		)
		(fp_line
			(start 0.12065 -0.2794)
			(end 0.12065 -0.3048)
			(stroke
				(width 0.1)
				(type default)
			)
			(layer "F.Fab")
		)
		(fp_line
			(start 0.12065 -0.3048)
			(end 0.67945 -0.3048)
			(stroke
				(width 0.1)
				(type default)
			)
			(layer "F.Fab")
		)
		(fp_line
			(start 0.67945 -0.3048)
			(end 0.67945 0.3048)
			(stroke
				(width 0.1)
				(type default)
			)
			(layer "F.Fab")
		)
		(fp_line
			(start -0.67945 -0.305054)
			(end -0.12065 -0.305054)
			(stroke
				(width 0.1)
				(type default)
			)
			(layer "F.Fab")
		)
		(fp_line
			(start -0.12065 -0.305054)
			(end -0.12065 -0.2794)
			(stroke
				(width 0.1)
				(type default)
			)
			(layer "F.Fab")
		)
		(pad "1" smd circle
			(at -0.40005 0 270)
			(size 0 0)
			(layers "F.Cu" "F.Mask" "F.Paste")
			(net "PEX2_MODE_SEL8")
		)
		(pad "2" smd circle
			(at 0.40005 0 270)
			(size 0 0)
			(layers "F.Cu" "F.Mask" "F.Paste")
			(net "P1V8_PEX")
		)
	)
	(footprint ""
		(layer "F.Cu")
		(at 202.278996 -59.577986 -90)
		(property "Reference" "R892"
			(at 0 0 270)
			(layer "F.SilkS")
			(hide yes)
			(effects
				(font
					(size 1.27 1.27)
				)
			)
		)
		(property "Value" ""
			(at 0 0 270)
			(layer "F.Fab")
			(effects
				(font
					(size 1.27 1.27)
				)
			)
		)
		(duplicate_pad_numbers_are_jumpers no)
		(fp_line
			(start -0.7874 0.4064)
			(end -0.7874 -0.4064)
			(stroke
				(width 0.1524)
				(type default)
			)
			(layer "F.SilkS")
		)
		(fp_line
			(start 0.7874 0.4064)
			(end -0.7874 0.4064)
			(stroke
				(width 0.1524)
				(type default)
			)
			(layer "F.SilkS")
		)
		(fp_line
			(start -0.7874 -0.4064)
			(end 0.7874 -0.4064)
			(stroke
				(width 0.1524)
				(type default)
			)
			(layer "F.SilkS")
		)
		(fp_line
			(start 0.7874 -0.4064)
			(end 0.7874 0.4064)
			(stroke
				(width 0.1524)
				(type default)
			)
			(layer "F.SilkS")
		)
		(fp_line
			(start -0.67945 0.3048)
			(end -0.67945 -0.305054)
			(stroke
				(width 0.1)
				(type default)
			)
			(layer "F.Fab")
		)
		(fp_line
			(start -0.12065 0.3048)
			(end -0.67945 0.3048)
			(stroke
				(width 0.1)
				(type default)
			)
			(layer "F.Fab")
		)
		(fp_line
			(start 0.120396 0.3048)
			(end 0.120396 0.2794)
			(stroke
				(width 0.1)
				(type default)
			)
			(layer "F.Fab")
		)
		(fp_line
			(start 0.67945 0.3048)
			(end 0.120396 0.3048)
			(stroke
				(width 0.1)
				(type default)
			)
			(layer "F.Fab")
		)
		(fp_line
			(start -0.12065 0.2794)
			(end -0.12065 0.3048)
			(stroke
				(width 0.1)
				(type default)
			)
			(layer "F.Fab")
		)
		(fp_line
			(start 0.120396 0.2794)
			(end -0.12065 0.2794)
			(stroke
				(width 0.1)
				(type default)
			)
			(layer "F.Fab")
		)
		(fp_line
			(start -0.12065 -0.2794)
			(end 0.12065 -0.2794)
			(stroke
				(width 0.1)
				(type default)
			)
			(layer "F.Fab")
		)
		(fp_line
			(start 0.12065 -0.2794)
			(end 0.12065 -0.3048)
			(stroke
				(width 0.1)
				(type default)
			)
			(layer "F.Fab")
		)
		(fp_line
			(start 0.12065 -0.3048)
			(end 0.67945 -0.3048)
			(stroke
				(width 0.1)
				(type default)
			)
			(layer "F.Fab")
		)
		(fp_line
			(start 0.67945 -0.3048)
			(end 0.67945 0.3048)
			(stroke
				(width 0.1)
				(type default)
			)
			(layer "F.Fab")
		)
		(fp_line
			(start -0.67945 -0.305054)
			(end -0.12065 -0.305054)
			(stroke
				(width 0.1)
				(type default)
			)
			(layer "F.Fab")
		)
		(fp_line
			(start -0.12065 -0.305054)
			(end -0.12065 -0.2794)
			(stroke
				(width 0.1)
				(type default)
			)
			(layer "F.Fab")
		)
		(pad "1" smd circle
			(at -0.40005 0 270)
			(size 0 0)
			(layers "F.Cu" "F.Mask" "F.Paste")
			(net "P3V3_SSD7")
		)
		(pad "2" smd circle
			(at 0.40005 0 270)
			(size 0 0)
			(layers "F.Cu" "F.Mask" "F.Paste")
			(net "PWRGD_P3V3_SSD7")
		)
	)
	(footprint ""
		(layer "F.Cu")
		(at 386.70738 -356.244906 90)
		(property "Reference" "C760"
			(at 0 0 90)
			(layer "F.SilkS")
			(hide yes)
			(effects
				(font
					(size 1.27 1.27)
				)
			)
		)
		(property "Value" ""
			(at 0 0 90)
			(layer "F.Fab")
			(effects
				(font
					(size 1.27 1.27)
				)
			)
		)
		(duplicate_pad_numbers_are_jumpers no)
		(fp_line
			(start 0.299974 -0.150114)
			(end 0.299974 0.150114)
			(stroke
				(width 0.1)
				(type default)
			)
			(layer "F.Fab")
		)
		(fp_line
			(start -0.299974 -0.150114)
			(end 0.299974 -0.150114)
			(stroke
				(width 0.1)
				(type default)
			)
			(layer "F.Fab")
		)
		(fp_line
			(start 0.299974 0.150114)
			(end -0.299974 0.150114)
			(stroke
				(width 0.1)
				(type default)
			)
			(layer "F.Fab")
		)
		(fp_line
			(start -0.299974 0.150114)
			(end -0.299974 -0.150114)
			(stroke
				(width 0.1)
				(type default)
			)
			(layer "F.Fab")
		)
		(pad "1" smd rect
			(at -0.2667 0 90)
			(size 0.3048 0.381)
			(layers "F.Cu" "F.Mask" "F.Paste")
			(net "P5E_PEX3_STN5_TX_DP<80>")
		)
		(pad "2" smd rect
			(at 0.2667 0 90)
			(size 0.3048 0.381)
			(layers "F.Cu" "F.Mask" "F.Paste")
			(net "P5E_PEX3_STN5_TX_C_DP<80>")
		)
	)
	(footprint ""
		(layer "F.Cu")
		(at 122.023124 -164.837872)
		(property "Reference" "R6670"
			(at 0 0 0)
			(layer "F.SilkS")
			(hide yes)
			(effects
				(font
					(size 1.27 1.27)
				)
			)
		)
		(property "Value" ""
			(at 0 0 0)
			(layer "F.Fab")
			(effects
				(font
					(size 1.27 1.27)
				)
			)
		)
		(duplicate_pad_numbers_are_jumpers no)
		(fp_line
			(start -0.7874 -0.4064)
			(end 0.7874 -0.4064)
			(stroke
				(width 0.1524)
				(type default)
			)
			(layer "F.SilkS")
		)
		(fp_line
			(start -0.7874 0.4064)
			(end -0.7874 -0.4064)
			(stroke
				(width 0.1524)
				(type default)
			)
			(layer "F.SilkS")
		)
		(fp_line
			(start 0.7874 -0.4064)
			(end 0.7874 0.4064)
			(stroke
				(width 0.1524)
				(type default)
			)
			(layer "F.SilkS")
		)
		(fp_line
			(start 0.7874 0.4064)
			(end -0.7874 0.4064)
			(stroke
				(width 0.1524)
				(type default)
			)
			(layer "F.SilkS")
		)
		(fp_line
			(start -0.67945 -0.305054)
			(end -0.12065 -0.305054)
			(stroke
				(width 0.1)
				(type default)
			)
			(layer "F.Fab")
		)
		(fp_line
			(start -0.67945 0.3048)
			(end -0.67945 -0.305054)
			(stroke
				(width 0.1)
				(type default)
			)
			(layer "F.Fab")
		)
		(fp_line
			(start -0.12065 -0.305054)
			(end -0.12065 -0.2794)
			(stroke
				(width 0.1)
				(type default)
			)
			(layer "F.Fab")
		)
		(fp_line
			(start -0.12065 -0.2794)
			(end 0.12065 -0.2794)
			(stroke
				(width 0.1)
				(type default)
			)
			(layer "F.Fab")
		)
		(fp_line
			(start -0.12065 0.2794)
			(end -0.12065 0.3048)
			(stroke
				(width 0.1)
				(type default)
			)
			(layer "F.Fab")
		)
		(fp_line
			(start -0.12065 0.3048)
			(end -0.67945 0.3048)
			(stroke
				(width 0.1)
				(type default)
			)
			(layer "F.Fab")
		)
		(fp_line
			(start 0.120396 0.2794)
			(end -0.12065 0.2794)
			(stroke
				(width 0.1)
				(type default)
			)
			(layer "F.Fab")
		)
		(fp_line
			(start 0.120396 0.3048)
			(end 0.120396 0.2794)
			(stroke
				(width 0.1)
				(type default)
			)
			(layer "F.Fab")
		)
		(fp_line
			(start 0.12065 -0.3048)
			(end 0.67945 -0.3048)
			(stroke
				(width 0.1)
				(type default)
			)
			(layer "F.Fab")
		)
		(fp_line
			(start 0.12065 -0.2794)
			(end 0.12065 -0.3048)
			(stroke
				(width 0.1)
				(type default)
			)
			(layer "F.Fab")
		)
		(fp_line
			(start 0.67945 -0.3048)
			(end 0.67945 0.3048)
			(stroke
				(width 0.1)
				(type default)
			)
			(layer "F.Fab")
		)
		(fp_line
			(start 0.67945 0.3048)
			(end 0.120396 0.3048)
			(stroke
				(width 0.1)
				(type default)
			)
			(layer "F.Fab")
		)
		(pad "1" smd circle
			(at -0.40005 0)
			(size 0 0)
			(layers "F.Cu" "F.Mask" "F.Paste")
			(net "NIC1_CLK_EN_BUF_R_N")
		)
		(pad "2" smd circle
			(at 0.40005 0)
			(size 0 0)
			(layers "F.Cu" "F.Mask" "F.Paste")
			(net "P3V3")
		)
	)
	(footprint ""
		(layer "F.Cu")
		(at 429.939704 -87.349076 -90)
		(property "Reference" "R402"
			(at 0 0 270)
			(layer "F.SilkS")
			(hide yes)
			(effects
				(font
					(size 1.27 1.27)
				)
			)
		)
		(property "Value" ""
			(at 0 0 270)
			(layer "F.Fab")
			(effects
				(font
					(size 1.27 1.27)
				)
			)
		)
		(duplicate_pad_numbers_are_jumpers no)
		(fp_line
			(start -0.7874 0.4064)
			(end -0.7874 -0.4064)
			(stroke
				(width 0.1524)
				(type default)
			)
			(layer "F.SilkS")
		)
		(fp_line
			(start 0.7874 0.4064)
			(end -0.7874 0.4064)
			(stroke
				(width 0.1524)
				(type default)
			)
			(layer "F.SilkS")
		)
		(fp_line
			(start -0.7874 -0.4064)
			(end 0.7874 -0.4064)
			(stroke
				(width 0.1524)
				(type default)
			)
			(layer "F.SilkS")
		)
		(fp_line
			(start 0.7874 -0.4064)
			(end 0.7874 0.4064)
			(stroke
				(width 0.1524)
				(type default)
			)
			(layer "F.SilkS")
		)
		(fp_line
			(start -0.67945 0.3048)
			(end -0.67945 -0.305054)
			(stroke
				(width 0.1)
				(type default)
			)
			(layer "F.Fab")
		)
		(fp_line
			(start -0.12065 0.3048)
			(end -0.67945 0.3048)
			(stroke
				(width 0.1)
				(type default)
			)
			(layer "F.Fab")
		)
		(fp_line
			(start 0.120396 0.3048)
			(end 0.120396 0.2794)
			(stroke
				(width 0.1)
				(type default)
			)
			(layer "F.Fab")
		)
		(fp_line
			(start 0.67945 0.3048)
			(end 0.120396 0.3048)
			(stroke
				(width 0.1)
				(type default)
			)
			(layer "F.Fab")
		)
		(fp_line
			(start -0.12065 0.2794)
			(end -0.12065 0.3048)
			(stroke
				(width 0.1)
				(type default)
			)
			(layer "F.Fab")
		)
		(fp_line
			(start 0.120396 0.2794)
			(end -0.12065 0.2794)
			(stroke
				(width 0.1)
				(type default)
			)
			(layer "F.Fab")
		)
		(fp_line
			(start -0.12065 -0.2794)
			(end 0.12065 -0.2794)
			(stroke
				(width 0.1)
				(type default)
			)
			(layer "F.Fab")
		)
		(fp_line
			(start 0.12065 -0.2794)
			(end 0.12065 -0.3048)
			(stroke
				(width 0.1)
				(type default)
			)
			(layer "F.Fab")
		)
		(fp_line
			(start 0.12065 -0.3048)
			(end 0.67945 -0.3048)
			(stroke
				(width 0.1)
				(type default)
			)
			(layer "F.Fab")
		)
		(fp_line
			(start 0.67945 -0.3048)
			(end 0.67945 0.3048)
			(stroke
				(width 0.1)
				(type default)
			)
			(layer "F.Fab")
		)
		(fp_line
			(start -0.67945 -0.305054)
			(end -0.12065 -0.305054)
			(stroke
				(width 0.1)
				(type default)
			)
			(layer "F.Fab")
		)
		(fp_line
			(start -0.12065 -0.305054)
			(end -0.12065 -0.2794)
			(stroke
				(width 0.1)
				(type default)
			)
			(layer "F.Fab")
		)
		(pad "1" smd circle
			(at -0.40005 0 270)
			(size 0 0)
			(layers "F.Cu" "F.Mask" "F.Paste")
			(net "RST_NIC7_PERST0_R_N")
		)
		(pad "2" smd circle
			(at 0.40005 0 270)
			(size 0 0)
			(layers "F.Cu" "F.Mask" "F.Paste")
			(net "RST_HP_NIC7_BUF_N")
		)
	)
)
